(kicad_pcb
	(version 20260206)
	(generator "pcbnew")
	(generator_version "10.0")
	(general
		(thickness 1.6)
		(legacy_teardrops no)
	)
	(paper "A4")
	(title_block
		(title "baseboard — 13948-1b.1110WZS1818.brd")
		(comment 1 "Honey Badger (Wiwynn) / footprints 626-633 of 2523")
	)
	(layers
		(0 "F.Cu" signal "TOP")
		(4 "In1.Cu" signal "L2GND")
		(6 "In2.Cu" signal "L3")
		(8 "In3.Cu" signal "L4VCC")
		(10 "In4.Cu" signal "L5VCC")
		(12 "In5.Cu" signal "L6")
		(14 "In6.Cu" signal "L7GND")
		(2 "B.Cu" signal "BOTTOM")
		(9 "F.Adhes" user "F.Adhesive")
		(11 "B.Adhes" user "B.Adhesive")
		(13 "F.Paste" user "Package Geometry/Pastemask Top")
		(15 "B.Paste" user "Package Geometry/Pastemask Bottom")
		(5 "F.SilkS" user "Ref Des/Silkscreen Top")
		(7 "B.SilkS" user "Ref Des/Silkscreen Bottom")
		(1 "F.Mask" user "Board Geometry/Soldermask Top")
		(3 "B.Mask" user "Board Geometry/Soldermask Bottom")
		(17 "Dwgs.User" user "User.Drawings")
		(19 "Cmts.User" user "User.Comments")
		(21 "Eco1.User" user "User.Eco1")
		(23 "Eco2.User" user "User.Eco2")
		(25 "Edge.Cuts" user "Board Geometry/Outline")
		(27 "Margin" user)
		(31 "F.CrtYd" user "Package Geometry/Place Bound Top")
		(29 "B.CrtYd" user "Package Geometry/Place Bound Bottom")
		(35 "F.Fab" user "Ref Des/Assembly Top")
		(33 "B.Fab" user "Ref Des/Assembly Bottom")
	)
	(footprint ""
		(layer "F.Cu")
		(at 317.290958 -61.341 -90)
		(property "Reference" "R254"
			(at 0 0 270)
			(layer "F.SilkS")
			(hide yes)
			(effects
				(font
					(size 1.27 1.27)
				)
			)
		)
		(property "Value" "0R2J-2-GP"
			(at 0.064008 -3.993896 270)
			(unlocked yes)
			(layer "F.Fab")
			(hide yes)
			(effects
				(font
					(size 1.016 1.016)
					(thickness 0.1524)
				)
			)
		)
		(property "Device Type" "R402H16"
			(at 0.064008 -5.517896 270)
			(unlocked yes)
			(layer "F.Fab")
			(hide yes)
			(effects
				(font
					(size 1.016 1.016)
					(thickness 0.1524)
				)
			)
		)
		(duplicate_pad_numbers_are_jumpers no)
		(fp_line
			(start -0.508 -0.9398)
			(end -0.508 0.9398)
			(stroke
				(width 0.1524)
				(type default)
			)
			(layer "F.SilkS")
		)
		(fp_line
			(start 0.508 -0.9398)
			(end -0.508 -0.9398)
			(stroke
				(width 0.1524)
				(type default)
			)
			(layer "F.SilkS")
		)
		(fp_rect
			(start -0.508 0.9398)
			(end 0.508 -0.9398)
			(stroke
				(width 0)
				(type default)
			)
			(fill no)
			(layer "F.CrtYd")
		)
		(fp_rect
			(start -0.508 0.9398)
			(end 0.508 -0.9398)
			(stroke
				(width 0)
				(type default)
			)
			(fill no)
			(layer "F.Fab")
		)
		(pad "1" smd custom
			(at 0 -0.4445 270)
			(size 0.1397 0.1397)
			(layers "F.Cu" "F.Mask" "F.Paste")
			(net "BMC_MBC_I2C_E_SCL")
			(options
				(clearance outline)
				(anchor circle)
			)
			(primitives
				(gr_poly
					(pts
						(arc
							(start -0.1778 -0.2794)
							(mid -0.249642 -0.249642)
							(end -0.2794 -0.1778)
						)
						(arc
							(start -0.2794 0.1778)
							(mid -0.249642 0.249642)
							(end -0.1778 0.2794)
						)
						(arc
							(start 0.1778 0.2794)
							(mid 0.249642 0.249642)
							(end 0.2794 0.1778)
						)
						(arc
							(start 0.2794 -0.1778)
							(mid 0.249642 -0.249642)
							(end 0.1778 -0.2794)
						)
					)
					(width 0)
					(fill yes)
				)
			)
		)
		(pad "2" smd custom
			(at 0 0.4445 270)
			(size 0.1397 0.1397)
			(layers "F.Cu" "F.Mask" "F.Paste")
			(net "I2C_BMC_MSB_CLK_R")
			(options
				(clearance outline)
				(anchor circle)
			)
			(primitives
				(gr_poly
					(pts
						(arc
							(start -0.1778 -0.2794)
							(mid -0.249642 -0.249642)
							(end -0.2794 -0.1778)
						)
						(arc
							(start -0.2794 0.1778)
							(mid -0.249642 0.249642)
							(end -0.1778 0.2794)
						)
						(arc
							(start 0.1778 0.2794)
							(mid 0.249642 0.249642)
							(end 0.2794 0.1778)
						)
						(arc
							(start 0.2794 -0.1778)
							(mid 0.249642 -0.249642)
							(end 0.1778 -0.2794)
						)
					)
					(width 0)
					(fill yes)
				)
			)
		)
	)
	(footprint ""
		(layer "F.Cu")
		(at 107.88777 -70.9168 90)
		(property "Reference" "R592"
			(at 0 0 90)
			(layer "F.SilkS")
			(hide yes)
			(effects
				(font
					(size 1.27 1.27)
				)
			)
		)
		(property "Value" "4K7R2F-GP"
			(at 0.064008 -3.993896 90)
			(unlocked yes)
			(layer "F.Fab")
			(hide yes)
			(effects
				(font
					(size 1.016 1.016)
					(thickness 0.1524)
				)
			)
		)
		(property "Device Type" "R402H16"
			(at 0.064008 -5.517896 90)
			(unlocked yes)
			(layer "F.Fab")
			(hide yes)
			(effects
				(font
					(size 1.016 1.016)
					(thickness 0.1524)
				)
			)
		)
		(duplicate_pad_numbers_are_jumpers no)
		(fp_line
			(start 0.508 -0.9398)
			(end -0.508 -0.9398)
			(stroke
				(width 0.1524)
				(type default)
			)
			(layer "F.SilkS")
		)
		(fp_line
			(start -0.508 -0.9398)
			(end -0.508 0.9398)
			(stroke
				(width 0.1524)
				(type default)
			)
			(layer "F.SilkS")
		)
		(fp_rect
			(start -0.508 0.9398)
			(end 0.508 -0.9398)
			(stroke
				(width 0)
				(type default)
			)
			(fill no)
			(layer "F.CrtYd")
		)
		(fp_rect
			(start -0.508 0.9398)
			(end 0.508 -0.9398)
			(stroke
				(width 0)
				(type default)
			)
			(fill no)
			(layer "F.Fab")
		)
		(pad "1" smd custom
			(at 0 -0.4445 90)
			(size 0.1397 0.1397)
			(layers "F.Cu" "F.Mask" "F.Paste")
			(net "P3V3_STBY")
			(options
				(clearance outline)
				(anchor circle)
			)
			(primitives
				(gr_poly
					(pts
						(arc
							(start -0.1778 -0.2794)
							(mid -0.249642 -0.249642)
							(end -0.2794 -0.1778)
						)
						(arc
							(start -0.2794 0.1778)
							(mid -0.249642 0.249642)
							(end -0.1778 0.2794)
						)
						(arc
							(start 0.1778 0.2794)
							(mid 0.249642 0.249642)
							(end 0.2794 0.1778)
						)
						(arc
							(start 0.2794 -0.1778)
							(mid 0.249642 -0.249642)
							(end 0.1778 -0.2794)
						)
					)
					(width 0)
					(fill yes)
				)
			)
		)
		(pad "2" smd custom
			(at 0 0.4445 90)
			(size 0.1397 0.1397)
			(layers "F.Cu" "F.Mask" "F.Paste")
			(net "TEMP_4_A0")
			(options
				(clearance outline)
				(anchor circle)
			)
			(primitives
				(gr_poly
					(pts
						(arc
							(start -0.1778 -0.2794)
							(mid -0.249642 -0.249642)
							(end -0.2794 -0.1778)
						)
						(arc
							(start -0.2794 0.1778)
							(mid -0.249642 0.249642)
							(end -0.1778 0.2794)
						)
						(arc
							(start 0.1778 0.2794)
							(mid 0.249642 0.249642)
							(end 0.2794 0.1778)
						)
						(arc
							(start 0.2794 -0.1778)
							(mid 0.249642 -0.249642)
							(end 0.1778 -0.2794)
						)
					)
					(width 0)
					(fill yes)
				)
			)
		)
	)
	(footprint ""
		(layer "F.Cu")
		(at 165.1 -115.062 90)
		(property "Reference" "PR161"
			(at 0 0 90)
			(layer "F.SilkS")
			(hide yes)
			(effects
				(font
					(size 1.27 1.27)
				)
			)
		)
		(property "Value" "4K87R2F-GP"
			(at 0.064008 -3.993896 90)
			(unlocked yes)
			(layer "F.Fab")
			(hide yes)
			(effects
				(font
					(size 1.016 1.016)
					(thickness 0.1524)
				)
			)
		)
		(property "Device Type" "R402H16"
			(at 0.064008 -5.517896 90)
			(unlocked yes)
			(layer "F.Fab")
			(hide yes)
			(effects
				(font
					(size 1.016 1.016)
					(thickness 0.1524)
				)
			)
		)
		(duplicate_pad_numbers_are_jumpers no)
		(fp_line
			(start 0.508 -0.9398)
			(end -0.508 -0.9398)
			(stroke
				(width 0.1524)
				(type default)
			)
			(layer "F.SilkS")
		)
		(fp_line
			(start -0.508 -0.9398)
			(end -0.508 0.9398)
			(stroke
				(width 0.1524)
				(type default)
			)
			(layer "F.SilkS")
		)
		(fp_rect
			(start -0.508 0.9398)
			(end 0.508 -0.9398)
			(stroke
				(width 0)
				(type default)
			)
			(fill no)
			(layer "F.CrtYd")
		)
		(fp_rect
			(start -0.508 0.9398)
			(end 0.508 -0.9398)
			(stroke
				(width 0)
				(type default)
			)
			(fill no)
			(layer "F.Fab")
		)
		(pad "1" smd custom
			(at 0 -0.4445 90)
			(size 0.1397 0.1397)
			(layers "F.Cu" "F.Mask" "F.Paste")
			(net "P0V9_E_VFB_R")
			(options
				(clearance outline)
				(anchor circle)
			)
			(primitives
				(gr_poly
					(pts
						(arc
							(start -0.1778 -0.2794)
							(mid -0.249642 -0.249642)
							(end -0.2794 -0.1778)
						)
						(arc
							(start -0.2794 0.1778)
							(mid -0.249642 0.249642)
							(end -0.1778 0.2794)
						)
						(arc
							(start 0.1778 0.2794)
							(mid 0.249642 0.249642)
							(end 0.2794 0.1778)
						)
						(arc
							(start 0.2794 -0.1778)
							(mid 0.249642 -0.249642)
							(end 0.1778 -0.2794)
						)
					)
					(width 0)
					(fill yes)
				)
			)
		)
		(pad "2" smd custom
			(at 0 0.4445 90)
			(size 0.1397 0.1397)
			(layers "F.Cu" "F.Mask" "F.Paste")
			(net "P0V9_E_VFB")
			(options
				(clearance outline)
				(anchor circle)
			)
			(primitives
				(gr_poly
					(pts
						(arc
							(start -0.1778 -0.2794)
							(mid -0.249642 -0.249642)
							(end -0.2794 -0.1778)
						)
						(arc
							(start -0.2794 0.1778)
							(mid -0.249642 0.249642)
							(end -0.1778 0.2794)
						)
						(arc
							(start 0.1778 0.2794)
							(mid 0.249642 0.249642)
							(end 0.2794 0.1778)
						)
						(arc
							(start 0.2794 -0.1778)
							(mid 0.249642 -0.249642)
							(end 0.1778 -0.2794)
						)
					)
					(width 0)
					(fill yes)
				)
			)
		)
	)
	(footprint ""
		(layer "F.Cu")
		(at 121.29897 -114.3 180)
		(property "Reference" "SC1067"
			(at 0 0 180)
			(layer "F.SilkS")
			(hide yes)
			(effects
				(font
					(size 1.27 1.27)
				)
			)
		)
		(property "Value" "SCD01U10V1KX-GP"
			(at -2.8321 -1.7399 180)
			(unlocked yes)
			(layer "F.Fab")
			(hide yes)
			(effects
				(font
					(size 1.016 1.016)
					(thickness 0.1524)
				)
			)
		)
		(property "Device Type" "C0201H13"
			(at -2.8321 -3.2639 180)
			(unlocked yes)
			(layer "F.Fab")
			(hide yes)
			(effects
				(font
					(size 1.016 1.016)
					(thickness 0.1524)
				)
			)
		)
		(duplicate_pad_numbers_are_jumpers no)
		(fp_rect
			(start -0.2794 0.6477)
			(end 0.2794 -0.6477)
			(stroke
				(width 0)
				(type default)
			)
			(fill no)
			(layer "F.CrtYd")
		)
		(fp_rect
			(start -0.2794 0.6477)
			(end 0.2794 -0.6477)
			(stroke
				(width 0)
				(type default)
			)
			(fill no)
			(layer "F.Fab")
		)
		(pad "1" smd custom
			(at 0 -0.2794 180)
			(size 0.0762 0.0762)
			(layers "F.Cu" "F.Mask" "F.Paste")
			(net "SAS_HDD_TX0_N")
			(options
				(clearance outline)
				(anchor circle)
			)
			(primitives
				(gr_poly
					(pts
						(arc
							(start 0.1524 -0.127)
							(mid 0.137521 -0.162921)
							(end 0.1016 -0.1778)
						)
						(arc
							(start -0.1016 -0.1778)
							(mid -0.137521 -0.162921)
							(end -0.1524 -0.127)
						)
						(arc
							(start -0.1524 0.127)
							(mid -0.137521 0.162921)
							(end -0.1016 0.1778)
						)
						(arc
							(start 0.1016 0.1778)
							(mid 0.137521 0.162921)
							(end 0.1524 0.127)
						)
					)
					(width 0)
					(fill yes)
				)
			)
		)
		(pad "2" smd custom
			(at 0 0.2794 180)
			(size 0.0762 0.0762)
			(layers "F.Cu" "F.Mask" "F.Paste")
			(net "SAS_EXP_GF_TX_DN4")
			(options
				(clearance outline)
				(anchor circle)
			)
			(primitives
				(gr_poly
					(pts
						(arc
							(start 0.1524 -0.127)
							(mid 0.137521 -0.162921)
							(end 0.1016 -0.1778)
						)
						(arc
							(start -0.1016 -0.1778)
							(mid -0.137521 -0.162921)
							(end -0.1524 -0.127)
						)
						(arc
							(start -0.1524 0.127)
							(mid -0.137521 0.162921)
							(end -0.1016 0.1778)
						)
						(arc
							(start 0.1016 0.1778)
							(mid 0.137521 0.162921)
							(end 0.1524 0.127)
						)
					)
					(width 0)
					(fill yes)
				)
			)
		)
	)
	(footprint ""
		(layer "F.Cu")
		(at 284.988 -156.464)
		(property "Reference" "R23"
			(at 0 0 0)
			(layer "F.SilkS")
			(hide yes)
			(effects
				(font
					(size 1.27 1.27)
				)
			)
		)
		(property "Value" "10KR2F-2-GP"
			(at 0.064008 -3.993896 0)
			(unlocked yes)
			(layer "F.Fab")
			(hide yes)
			(effects
				(font
					(size 1.016 1.016)
					(thickness 0.1524)
				)
			)
		)
		(property "Device Type" "R402H16"
			(at 0.064008 -5.517896 0)
			(unlocked yes)
			(layer "F.Fab")
			(hide yes)
			(effects
				(font
					(size 1.016 1.016)
					(thickness 0.1524)
				)
			)
		)
		(duplicate_pad_numbers_are_jumpers no)
		(fp_line
			(start -0.508 -0.9398)
			(end -0.508 0.9398)
			(stroke
				(width 0.1524)
				(type default)
			)
			(layer "F.SilkS")
		)
		(fp_line
			(start 0.508 -0.9398)
			(end -0.508 -0.9398)
			(stroke
				(width 0.1524)
				(type default)
			)
			(layer "F.SilkS")
		)
		(fp_rect
			(start -0.508 0.9398)
			(end 0.508 -0.9398)
			(stroke
				(width 0)
				(type default)
			)
			(fill no)
			(layer "F.CrtYd")
		)
		(fp_rect
			(start -0.508 0.9398)
			(end 0.508 -0.9398)
			(stroke
				(width 0)
				(type default)
			)
			(fill no)
			(layer "F.Fab")
		)
		(pad "1" smd custom
			(at 0 -0.4445)
			(size 0.1397 0.1397)
			(layers "F.Cu" "F.Mask" "F.Paste")
			(net "BMC_LSI_BOARD")
			(options
				(clearance outline)
				(anchor circle)
			)
			(primitives
				(gr_poly
					(pts
						(arc
							(start -0.1778 -0.2794)
							(mid -0.249642 -0.249642)
							(end -0.2794 -0.1778)
						)
						(arc
							(start -0.2794 0.1778)
							(mid -0.249642 0.249642)
							(end -0.1778 0.2794)
						)
						(arc
							(start 0.1778 0.2794)
							(mid 0.249642 0.249642)
							(end 0.2794 0.1778)
						)
						(arc
							(start 0.2794 -0.1778)
							(mid 0.249642 -0.249642)
							(end 0.1778 -0.2794)
						)
					)
					(width 0)
					(fill yes)
				)
			)
		)
		(pad "2" smd custom
			(at 0 0.4445)
			(size 0.1397 0.1397)
			(layers "F.Cu" "F.Mask" "F.Paste")
			(net "P3V3_STBY")
			(options
				(clearance outline)
				(anchor circle)
			)
			(primitives
				(gr_poly
					(pts
						(arc
							(start -0.1778 -0.2794)
							(mid -0.249642 -0.249642)
							(end -0.2794 -0.1778)
						)
						(arc
							(start -0.2794 0.1778)
							(mid -0.249642 0.249642)
							(end -0.1778 0.2794)
						)
						(arc
							(start 0.1778 0.2794)
							(mid 0.249642 0.249642)
							(end 0.2794 0.1778)
						)
						(arc
							(start 0.2794 -0.1778)
							(mid 0.249642 -0.249642)
							(end 0.1778 -0.2794)
						)
					)
					(width 0)
					(fill yes)
				)
			)
		)
	)
	(footprint ""
		(layer "F.Cu")
		(at 108.966 -239.141 90)
		(property "Reference" "SR948"
			(at 0 0 90)
			(layer "F.SilkS")
			(hide yes)
			(effects
				(font
					(size 1.27 1.27)
				)
			)
		)
		(property "Value" "4K7R2F-GP"
			(at 0.064008 -3.993896 90)
			(unlocked yes)
			(layer "F.Fab")
			(hide yes)
			(effects
				(font
					(size 1.016 1.016)
					(thickness 0.1524)
				)
			)
		)
		(property "Device Type" "R402H16"
			(at 0.064008 -5.517896 90)
			(unlocked yes)
			(layer "F.Fab")
			(hide yes)
			(effects
				(font
					(size 1.016 1.016)
					(thickness 0.1524)
				)
			)
		)
		(duplicate_pad_numbers_are_jumpers no)
		(fp_line
			(start 0.508 -0.9398)
			(end -0.508 -0.9398)
			(stroke
				(width 0.1524)
				(type default)
			)
			(layer "F.SilkS")
		)
		(fp_line
			(start -0.508 -0.9398)
			(end -0.508 0.9398)
			(stroke
				(width 0.1524)
				(type default)
			)
			(layer "F.SilkS")
		)
		(fp_rect
			(start -0.508 0.9398)
			(end 0.508 -0.9398)
			(stroke
				(width 0)
				(type default)
			)
			(fill no)
			(layer "F.CrtYd")
		)
		(fp_rect
			(start -0.508 0.9398)
			(end 0.508 -0.9398)
			(stroke
				(width 0)
				(type default)
			)
			(fill no)
			(layer "F.Fab")
		)
		(pad "1" smd custom
			(at 0 -0.4445 90)
			(size 0.1397 0.1397)
			(layers "F.Cu" "F.Mask" "F.Paste")
			(net "SAS_FAULT_LED7")
			(options
				(clearance outline)
				(anchor circle)
			)
			(primitives
				(gr_poly
					(pts
						(arc
							(start -0.1778 -0.2794)
							(mid -0.249642 -0.249642)
							(end -0.2794 -0.1778)
						)
						(arc
							(start -0.2794 0.1778)
							(mid -0.249642 0.249642)
							(end -0.1778 0.2794)
						)
						(arc
							(start 0.1778 0.2794)
							(mid 0.249642 0.249642)
							(end 0.2794 0.1778)
						)
						(arc
							(start 0.2794 -0.1778)
							(mid 0.249642 -0.249642)
							(end 0.1778 -0.2794)
						)
					)
					(width 0)
					(fill yes)
				)
			)
		)
		(pad "2" smd custom
			(at 0 0.4445 90)
			(size 0.1397 0.1397)
			(layers "F.Cu" "F.Mask" "F.Paste")
			(net "P3V3_STBY")
			(options
				(clearance outline)
				(anchor circle)
			)
			(primitives
				(gr_poly
					(pts
						(arc
							(start -0.1778 -0.2794)
							(mid -0.249642 -0.249642)
							(end -0.2794 -0.1778)
						)
						(arc
							(start -0.2794 0.1778)
							(mid -0.249642 0.249642)
							(end -0.1778 0.2794)
						)
						(arc
							(start 0.1778 0.2794)
							(mid 0.249642 0.249642)
							(end 0.2794 0.1778)
						)
						(arc
							(start 0.2794 -0.1778)
							(mid 0.249642 -0.249642)
							(end 0.1778 -0.2794)
						)
					)
					(width 0)
					(fill yes)
				)
			)
		)
	)
	(footprint ""
		(layer "F.Cu")
		(at 101.99497 -78.613)
		(property "Reference" "STP146"
			(at 0 0 0)
			(layer "F.SilkS")
			(hide yes)
			(effects
				(font
					(size 1.27 1.27)
				)
			)
		)
		(property "Value" "TPAD28"
			(at 0.0127 -1.8034 0)
			(unlocked yes)
			(layer "F.Fab")
			(hide yes)
			(effects
				(font
					(size 1.016 1.016)
					(thickness 0.1524)
				)
			)
		)
		(property "Device Type" "TPAD28"
			(at 0.0127 -3.3274 0)
			(unlocked yes)
			(layer "F.Fab")
			(hide yes)
			(effects
				(font
					(size 1.016 1.016)
					(thickness 0.1524)
				)
			)
		)
		(duplicate_pad_numbers_are_jumpers no)
		(fp_poly
			(pts
				(arc
					(start 0.3556 0)
					(mid -0.3556 0)
					(end 0.3556 0)
				)
			)
			(stroke
				(width 0)
				(type default)
			)
			(fill no)
			(layer "F.CrtYd")
		)
		(fp_poly
			(pts
				(arc
					(start 0.6096 0)
					(mid -0.6096 0)
					(end 0.6096 0)
				)
			)
			(stroke
				(width 0)
				(type default)
			)
			(fill no)
			(layer "F.Fab")
		)
		(pad "1" smd circle
			(at 0 0)
			(size 0.7112 0.7112)
			(layers "F.Cu" "F.Mask" "F.Paste")
			(net "JTAG_EXP_TDO_R")
		)
	)
	(footprint ""
		(layer "F.Cu")
		(at 92.27947 -106.426 90)
		(property "Reference" "SR818"
			(at 0 0 90)
			(layer "F.SilkS")
			(hide yes)
			(effects
				(font
					(size 1.27 1.27)
				)
			)
		)
		(property "Value" "4K75R2F-1-GP"
			(at 0.064008 -3.993896 90)
			(unlocked yes)
			(layer "F.Fab")
			(hide yes)
			(effects
				(font
					(size 1.016 1.016)
					(thickness 0.1524)
				)
			)
		)
		(property "Device Type" "R402H16"
			(at 0.064008 -5.517896 90)
			(unlocked yes)
			(layer "F.Fab")
			(hide yes)
			(effects
				(font
					(size 1.016 1.016)
					(thickness 0.1524)
				)
			)
		)
		(duplicate_pad_numbers_are_jumpers no)
		(fp_line
			(start 0.508 -0.9398)
			(end -0.508 -0.9398)
			(stroke
				(width 0.1524)
				(type default)
			)
			(layer "F.SilkS")
		)
		(fp_line
			(start -0.508 -0.9398)
			(end -0.508 0.9398)
			(stroke
				(width 0.1524)
				(type default)
			)
			(layer "F.SilkS")
		)
		(fp_rect
			(start -0.508 0.9398)
			(end 0.508 -0.9398)
			(stroke
				(width 0)
				(type default)
			)
			(fill no)
			(layer "F.CrtYd")
		)
		(fp_rect
			(start -0.508 0.9398)
			(end 0.508 -0.9398)
			(stroke
				(width 0)
				(type default)
			)
			(fill no)
			(layer "F.Fab")
		)
		(pad "1" smd custom
			(at 0 -0.4445 90)
			(size 0.1397 0.1397)
			(layers "F.Cu" "F.Mask" "F.Paste")
			(net "P1V8_E")
			(options
				(clearance outline)
				(anchor circle)
			)
			(primitives
				(gr_poly
					(pts
						(arc
							(start -0.1778 -0.2794)
							(mid -0.249642 -0.249642)
							(end -0.2794 -0.1778)
						)
						(arc
							(start -0.2794 0.1778)
							(mid -0.249642 0.249642)
							(end -0.1778 0.2794)
						)
						(arc
							(start 0.1778 0.2794)
							(mid 0.249642 0.249642)
							(end 0.2794 0.1778)
						)
						(arc
							(start 0.2794 -0.1778)
							(mid 0.249642 -0.249642)
							(end 0.1778 -0.2794)
						)
					)
					(width 0)
					(fill yes)
				)
			)
		)
		(pad "2" smd custom
			(at 0 0.4445 90)
			(size 0.1397 0.1397)
			(layers "F.Cu" "F.Mask" "F.Paste")
			(net "SAS_SMART_RX")
			(options
				(clearance outline)
				(anchor circle)
			)
			(primitives
				(gr_poly
					(pts
						(arc
							(start -0.1778 -0.2794)
							(mid -0.249642 -0.249642)
							(end -0.2794 -0.1778)
						)
						(arc
							(start -0.2794 0.1778)
							(mid -0.249642 0.249642)
							(end -0.1778 0.2794)
						)
						(arc
							(start 0.1778 0.2794)
							(mid 0.249642 0.249642)
							(end 0.2794 0.1778)
						)
						(arc
							(start 0.2794 -0.1778)
							(mid 0.249642 -0.249642)
							(end 0.1778 -0.2794)
						)
					)
					(width 0)
					(fill yes)
				)
			)
		)
	)
)
